(kicad_pcb
	(version 20241229)
	(generator "pcbnew")
	(generator_version "9.0")
	(general
		(thickness 1.62)
		(legacy_teardrops no)
	)
	(paper "A3")
	(title_block
		(title "COM Express 7 Baseboard")
		(date "2025-02-04")
		(rev "1.1.2")
		(company "Antmicro Ltd")
		(comment 1 "www.antmicro.com")
		(comment 9 "footprint 489 of 802 (J12), pads 44-83 of 450")
	)
	(layers
		(0 "F.Cu" signal)
		(4 "In1.Cu" signal)
		(6 "In2.Cu" signal)
		(8 "In3.Cu" signal)
		(10 "In4.Cu" signal)
		(12 "In5.Cu" signal)
		(14 "In6.Cu" signal)
		(2 "B.Cu" signal)
		(9 "F.Adhes" user "F.Adhesive")
		(11 "B.Adhes" user "B.Adhesive")
		(13 "F.Paste" user)
		(15 "B.Paste" user)
		(5 "F.SilkS" user "F.Silkscreen")
		(7 "B.SilkS" user "B.Silkscreen")
		(1 "F.Mask" user)
		(3 "B.Mask" user)
		(17 "Dwgs.User" user "User.Drawings")
		(19 "Cmts.User" user "User.Comments")
		(21 "Eco1.User" user "User.Eco1")
		(23 "Eco2.User" user "User.Eco2")
		(25 "Edge.Cuts" user)
		(27 "Margin" user)
		(31 "F.CrtYd" user "F.Courtyard")
		(29 "B.CrtYd" user "B.Courtyard")
		(35 "F.Fab" user)
		(33 "B.Fab" user)
	)
	(footprint "antmicro-footprints:EPT_401-51501-51"
		(layer "F.Cu")
		(at 203.275 159.81)
		(property "Reference" "J12"
			(at 30.975 -10.45 0)
			(layer "F.SilkS")
			(effects
				(font
					(size 0.7 0.7)
					(thickness 0.15)
				)
				(justify right top)
			)
		)
		(property "Value" "Plug_Bus_CE7_EPT_401-51501-51"
			(at -3.225 52.665 0)
			(layer "F.Fab")
			(hide yes)
			(effects
				(font
					(size 0.7 0.7)
					(thickness 0.15)
				)
				(justify left top)
			)
		)
		(property "Datasheet" "https://www.farnell.com/datasheets/1905093.pdf"
			(at 0 0 0)
			(layer "F.Fab")
			(hide yes)
			(effects
				(font
					(size 1.27 1.27)
					(thickness 0.15)
				)
			)
		)
		(property "Author" "Antmicro"
			(at 406.55 319.62 0)
			(layer "F.Fab")
			(hide yes)
			(effects
				(font
					(size 1 1)
					(thickness 0.15)
				)
			)
		)
		(property "License" "Apache-2.0"
			(at 406.55 319.62 0)
			(layer "F.Fab")
			(hide yes)
			(effects
				(font
					(size 1 1)
					(thickness 0.15)
				)
			)
		)
		(property "MPN" "401-51501-51"
			(at 406.55 319.62 0)
			(layer "F.Fab")
			(hide yes)
			(effects
				(font
					(size 1 1)
					(thickness 0.15)
				)
			)
		)
		(property "Manufacturer" "ept"
			(at 406.55 319.62 0)
			(layer "F.Fab")
			(hide yes)
			(effects
				(font
					(size 1 1)
					(thickness 0.15)
				)
			)
		)
		(sheetname "Com Express 7 Interfaces")
		(sheetfile "com_express_7_interfaces.kicad_sch")
		(attr smd)
		(pad "A39" smd rect
			(at -8.25 8.875)
			(size 0.3 1.75)
			(layers "F.Cu" "F.Mask" "F.Paste")
			(net 269 "/Com Express 7 Interfaces/PCIe_{B2Bx4}.TX0+")
			(pinfunction "PCIE_TX12+")
			(pintype "output")
			(teardrops
				(best_length_ratio 0.2)
				(max_length 1)
				(best_width_ratio 0.9)
				(max_width 2)
				(curved_edges yes)
				(filter_ratio 0.9)
				(enabled yes)
				(allow_two_segments yes)
				(prefer_zone_connections yes)
			)
		)
		(pad "A40" smd rect
			(at -7.75 8.875)
			(size 0.3 1.75)
			(layers "F.Cu" "F.Mask" "F.Paste")
			(net 267 "/Com Express 7 Interfaces/PCIe_{B2Bx4}.TX0-")
			(pinfunction "PCIE_TX12-")
			(pintype "output")
			(teardrops
				(best_length_ratio 0.2)
				(max_length 1)
				(best_width_ratio 0.9)
				(max_width 2)
				(curved_edges yes)
				(filter_ratio 0.9)
				(enabled yes)
				(allow_two_segments yes)
				(prefer_zone_connections yes)
			)
		)
		(pad "A41" smd rect
			(at -7.25 8.875)
			(size 0.3 1.75)
			(layers "F.Cu" "F.Mask" "F.Paste")
			(net 1 "GND")
			(pinfunction "GND(FIXED)")
			(pintype "passive")
			(teardrops
				(best_length_ratio 0.2)
				(max_length 1)
				(best_width_ratio 0.9)
				(max_width 2)
				(curved_edges yes)
				(filter_ratio 0.9)
				(enabled yes)
				(allow_two_segments yes)
				(prefer_zone_connections yes)
			)
		)
		(pad "A42" smd rect
			(at -6.75 8.875)
			(size 0.3 1.75)
			(layers "F.Cu" "F.Mask" "F.Paste")
			(net 312 "/2xUSB3.0+RJ45/USB_1.D-")
			(pinfunction "USB2-")
			(pintype "bidirectional")
			(teardrops
				(best_length_ratio 0.2)
				(max_length 1)
				(best_width_ratio 0.9)
				(max_width 2)
				(curved_edges yes)
				(filter_ratio 0.9)
				(enabled yes)
				(allow_two_segments yes)
				(prefer_zone_connections yes)
			)
		)
		(pad "A43" smd rect
			(at -6.25 8.875)
			(size 0.3 1.75)
			(layers "F.Cu" "F.Mask" "F.Paste")
			(net 313 "/2xUSB3.0+RJ45/USB_1.D+")
			(pinfunction "USB2+")
			(pintype "bidirectional")
			(teardrops
				(best_length_ratio 0.2)
				(max_length 1)
				(best_width_ratio 0.9)
				(max_width 2)
				(curved_edges yes)
				(filter_ratio 0.9)
				(enabled yes)
				(allow_two_segments yes)
				(prefer_zone_connections yes)
			)
		)
		(pad "A44" smd rect
			(at -5.75 8.875)
			(size 0.3 1.75)
			(layers "F.Cu" "F.Mask" "F.Paste")
			(net 314 "/2xUSB3.0+RJ45/FLG_1")
			(pinfunction "~{USB_2_3_OC}")
			(pintype "input")
			(teardrops
				(best_length_ratio 0.2)
				(max_length 1)
				(best_width_ratio 0.9)
				(max_width 2)
				(curved_edges yes)
				(filter_ratio 0.9)
				(enabled yes)
				(allow_two_segments yes)
				(prefer_zone_connections yes)
			)
		)
		(pad "A45" smd rect
			(at -5.25 8.875)
			(size 0.3 1.75)
			(layers "F.Cu" "F.Mask" "F.Paste")
			(net 204 "/Backplane/USB.D-")
			(pinfunction "USB0-")
			(pintype "bidirectional")
			(teardrops
				(best_length_ratio 0.2)
				(max_length 1)
				(best_width_ratio 0.9)
				(max_width 2)
				(curved_edges yes)
				(filter_ratio 0.9)
				(enabled yes)
				(allow_two_segments yes)
				(prefer_zone_connections yes)
			)
		)
		(pad "A46" smd rect
			(at -4.75 8.875)
			(size 0.3 1.75)
			(layers "F.Cu" "F.Mask" "F.Paste")
			(net 206 "/Backplane/USB.D+")
			(pinfunction "USB0+")
			(pintype "bidirectional")
			(teardrops
				(best_length_ratio 0.2)
				(max_length 1)
				(best_width_ratio 0.9)
				(max_width 2)
				(curved_edges yes)
				(filter_ratio 0.9)
				(enabled yes)
				(allow_two_segments yes)
				(prefer_zone_connections yes)
			)
		)
		(pad "A47" smd rect
			(at -4.25 8.875)
			(size 0.3 1.75)
			(layers "F.Cu" "F.Mask" "F.Paste")
			(net 315 "Net-(J12H-VCC_RTC)")
			(pinfunction "VCC_RTC")
			(pintype "power_in")
			(teardrops
				(best_length_ratio 0.2)
				(max_length 1)
				(best_width_ratio 0.9)
				(max_width 2)
				(curved_edges yes)
				(filter_ratio 0.9)
				(enabled yes)
				(allow_two_segments yes)
				(prefer_zone_connections yes)
			)
		)
		(pad "A48" smd rect
			(at -3.75 8.875)
			(size 0.3 1.75)
			(layers "F.Cu" "F.Mask" "F.Paste")
			(net 316 "unconnected-(J12H-RSVD-PadA48)")
			(pinfunction "RSVD")
			(pintype "no_connect")
			(teardrops
				(best_length_ratio 0.2)
				(max_length 1)
				(best_width_ratio 0.9)
				(max_width 2)
				(curved_edges yes)
				(filter_ratio 0.9)
				(enabled yes)
				(allow_two_segments yes)
				(prefer_zone_connections yes)
			)
		)
		(pad "A49" smd rect
			(at -3.25 8.875)
			(size 0.3 1.75)
			(layers "F.Cu" "F.Mask" "F.Paste")
			(net 317 "unconnected-(J12B-GBE0_SDP-PadA49)")
			(pinfunction "GBE0_SDP")
			(pintype "bidirectional+no_connect")
			(teardrops
				(best_length_ratio 0.2)
				(max_length 1)
				(best_width_ratio 0.9)
				(max_width 2)
				(curved_edges yes)
				(filter_ratio 0.9)
				(enabled yes)
				(allow_two_segments yes)
				(prefer_zone_connections yes)
			)
		)
		(pad "A50" smd rect
			(at -2.75 8.875)
			(size 0.3 1.75)
			(layers "F.Cu" "F.Mask" "F.Paste")
			(net 318 "Net-(J12D-LPC_SERIRQ{slash}~{ESPI_CS1})")
			(pinfunction "LPC_SERIRQ/~{ESPI_CS1}")
			(pintype "bidirectional")
			(teardrops
				(best_length_ratio 0.2)
				(max_length 1)
				(best_width_ratio 0.9)
				(max_width 2)
				(curved_edges yes)
				(filter_ratio 0.9)
				(enabled yes)
				(allow_two_segments yes)
				(prefer_zone_connections yes)
			)
		)
		(pad "A51" smd rect
			(at -2.25 8.875)
			(size 0.3 1.75)
			(layers "F.Cu" "F.Mask" "F.Paste")
			(net 1 "GND")
			(pinfunction "GND(FIXED)")
			(pintype "passive")
			(teardrops
				(best_length_ratio 0.2)
				(max_length 1)
				(best_width_ratio 0.9)
				(max_width 2)
				(curved_edges yes)
				(filter_ratio 0.9)
				(enabled yes)
				(allow_two_segments yes)
				(prefer_zone_connections yes)
			)
		)
		(pad "A52" smd rect
			(at -1.75 8.875)
			(size 0.3 1.75)
			(layers "F.Cu" "F.Mask" "F.Paste")
			(net 319 "/Com Express 7 Interfaces/PCIe_{B1x2}.TX1+")
			(pinfunction "PCIE_TX5+")
			(pintype "output+no_connect")
			(teardrops
				(best_length_ratio 0.2)
				(max_length 1)
				(best_width_ratio 0.9)
				(max_width 2)
				(curved_edges yes)
				(filter_ratio 0.9)
				(enabled yes)
				(allow_two_segments yes)
				(prefer_zone_connections yes)
			)
		)
		(pad "A53" smd rect
			(at -1.25 8.875)
			(size 0.3 1.75)
			(layers "F.Cu" "F.Mask" "F.Paste")
			(net 320 "/Com Express 7 Interfaces/PCIe_{B1x2}.TX1-")
			(pinfunction "PCIE_TX5-")
			(pintype "output+no_connect")
			(teardrops
				(best_length_ratio 0.2)
				(max_length 1)
				(best_width_ratio 0.9)
				(max_width 2)
				(curved_edges yes)
				(filter_ratio 0.9)
				(enabled yes)
				(allow_two_segments yes)
				(prefer_zone_connections yes)
			)
		)
		(pad "A54" smd rect
			(at -0.75 8.875)
			(size 0.3 1.75)
			(layers "F.Cu" "F.Mask" "F.Paste")
			(net 321 "/Com Express 7 Interfaces/SDIO.DAT0")
			(pinfunction "GPI0")
			(pintype "input")
			(teardrops
				(best_length_ratio 0.2)
				(max_length 1)
				(best_width_ratio 0.9)
				(max_width 2)
				(curved_edges yes)
				(filter_ratio 0.9)
				(enabled yes)
				(allow_two_segments yes)
				(prefer_zone_connections yes)
			)
		)
		(pad "A55" smd rect
			(at -0.25 8.875)
			(size 0.3 1.75)
			(layers "F.Cu" "F.Mask" "F.Paste")
			(net 9 "/Com Express 7 Interfaces/PCIe_{B1x2}.TX0+")
			(pinfunction "PCIE_TX4+")
			(pintype "output")
			(teardrops
				(best_length_ratio 0.2)
				(max_length 1)
				(best_width_ratio 0.9)
				(max_width 2)
				(curved_edges yes)
				(filter_ratio 0.9)
				(enabled yes)
				(allow_two_segments yes)
				(prefer_zone_connections yes)
			)
		)
		(pad "A56" smd rect
			(at 0.25 8.875)
			(size 0.3 1.75)
			(layers "F.Cu" "F.Mask" "F.Paste")
			(net 11 "/Com Express 7 Interfaces/PCIe_{B1x2}.TX0-")
			(pinfunction "PCIE_TX4-")
			(pintype "output")
			(teardrops
				(best_length_ratio 0.2)
				(max_length 1)
				(best_width_ratio 0.9)
				(max_width 2)
				(curved_edges yes)
				(filter_ratio 0.9)
				(enabled yes)
				(allow_two_segments yes)
				(prefer_zone_connections yes)
			)
		)
		(pad "A57" smd rect
			(at 0.75 8.875)
			(size 0.3 1.75)
			(layers "F.Cu" "F.Mask" "F.Paste")
			(net 1 "GND")
			(pinfunction "GND")
			(pintype "passive")
			(teardrops
				(best_length_ratio 0.2)
				(max_length 1)
				(best_width_ratio 0.9)
				(max_width 2)
				(curved_edges yes)
				(filter_ratio 0.9)
				(enabled yes)
				(allow_two_segments yes)
				(prefer_zone_connections yes)
			)
		)
		(pad "A58" smd rect
			(at 1.25 8.875)
			(size 0.3 1.75)
			(layers "F.Cu" "F.Mask" "F.Paste")
			(net 212 "/Com Express 7 Interfaces/PCIe_{B1x4}.TX3+")
			(pinfunction "PCIE_TX3+")
			(pintype "output")
			(teardrops
				(best_length_ratio 0.2)
				(max_length 1)
				(best_width_ratio 0.9)
				(max_width 2)
				(curved_edges yes)
				(filter_ratio 0.9)
				(enabled yes)
				(allow_two_segments yes)
				(prefer_zone_connections yes)
			)
		)
		(pad "A59" smd rect
			(at 1.75 8.875)
			(size 0.3 1.75)
			(layers "F.Cu" "F.Mask" "F.Paste")
			(net 211 "/Com Express 7 Interfaces/PCIe_{B1x4}.TX3-")
			(pinfunction "PCIE_TX3-")
			(pintype "output")
			(teardrops
				(best_length_ratio 0.2)
				(max_length 1)
				(best_width_ratio 0.9)
				(max_width 2)
				(curved_edges yes)
				(filter_ratio 0.9)
				(enabled yes)
				(allow_two_segments yes)
				(prefer_zone_connections yes)
			)
		)
		(pad "A60" smd rect
			(at 2.25 8.875)
			(size 0.3 1.75)
			(layers "F.Cu" "F.Mask" "F.Paste")
			(net 1 "GND")
			(pinfunction "GND(FIXED)")
			(pintype "passive")
			(teardrops
				(best_length_ratio 0.2)
				(max_length 1)
				(best_width_ratio 0.9)
				(max_width 2)
				(curved_edges yes)
				(filter_ratio 0.9)
				(enabled yes)
				(allow_two_segments yes)
				(prefer_zone_connections yes)
			)
		)
		(pad "A61" smd rect
			(at 2.75 8.875)
			(size 0.3 1.75)
			(layers "F.Cu" "F.Mask" "F.Paste")
			(net 216 "/Com Express 7 Interfaces/PCIe_{B1x4}.TX2+")
			(pinfunction "PCIE_TX2+")
			(pintype "output")
			(teardrops
				(best_length_ratio 0.2)
				(max_length 1)
				(best_width_ratio 0.9)
				(max_width 2)
				(curved_edges yes)
				(filter_ratio 0.9)
				(enabled yes)
				(allow_two_segments yes)
				(prefer_zone_connections yes)
			)
		)
		(pad "A62" smd rect
			(at 3.25 8.875)
			(size 0.3 1.75)
			(layers "F.Cu" "F.Mask" "F.Paste")
			(net 215 "/Com Express 7 Interfaces/PCIe_{B1x4}.TX2-")
			(pinfunction "PCIE_TX2-")
			(pintype "output")
			(teardrops
				(best_length_ratio 0.2)
				(max_length 1)
				(best_width_ratio 0.9)
				(max_width 2)
				(curved_edges yes)
				(filter_ratio 0.9)
				(enabled yes)
				(allow_two_segments yes)
				(prefer_zone_connections yes)
			)
		)
		(pad "A63" smd rect
			(at 3.75 8.875)
			(size 0.3 1.75)
			(layers "F.Cu" "F.Mask" "F.Paste")
			(net 322 "/Com Express 7 Interfaces/SDIO.DAT1")
			(pinfunction "GPI1")
			(pintype "input")
			(teardrops
				(best_length_ratio 0.2)
				(max_length 1)
				(best_width_ratio 0.9)
				(max_width 2)
				(curved_edges yes)
				(filter_ratio 0.9)
				(enabled yes)
				(allow_two_segments yes)
				(prefer_zone_connections yes)
			)
		)
		(pad "A64" smd rect
			(at 4.25 8.875)
			(size 0.3 1.75)
			(layers "F.Cu" "F.Mask" "F.Paste")
			(net 220 "/Com Express 7 Interfaces/PCIe_{B1x4}.TX1+")
			(pinfunction "PCIE_TX1+")
			(pintype "output")
			(teardrops
				(best_length_ratio 0.2)
				(max_length 1)
				(best_width_ratio 0.9)
				(max_width 2)
				(curved_edges yes)
				(filter_ratio 0.9)
				(enabled yes)
				(allow_two_segments yes)
				(prefer_zone_connections yes)
			)
		)
		(pad "A65" smd rect
			(at 4.75 8.875)
			(size 0.3 1.75)
			(layers "F.Cu" "F.Mask" "F.Paste")
			(net 219 "/Com Express 7 Interfaces/PCIe_{B1x4}.TX1-")
			(pinfunction "PCIE_TX1-")
			(pintype "output")
			(teardrops
				(best_length_ratio 0.2)
				(max_length 1)
				(best_width_ratio 0.9)
				(max_width 2)
				(curved_edges yes)
				(filter_ratio 0.9)
				(enabled yes)
				(allow_two_segments yes)
				(prefer_zone_connections yes)
			)
		)
		(pad "A66" smd rect
			(at 5.25 8.875)
			(size 0.3 1.75)
			(layers "F.Cu" "F.Mask" "F.Paste")
			(net 1 "GND")
			(pinfunction "GND")
			(pintype "passive")
			(teardrops
				(best_length_ratio 0.2)
				(max_length 1)
				(best_width_ratio 0.9)
				(max_width 2)
				(curved_edges yes)
				(filter_ratio 0.9)
				(enabled yes)
				(allow_two_segments yes)
				(prefer_zone_connections yes)
			)
		)
		(pad "A67" smd rect
			(at 5.75 8.875)
			(size 0.3 1.75)
			(layers "F.Cu" "F.Mask" "F.Paste")
			(net 323 "/Com Express 7 Interfaces/SDIO.DAT2")
			(pinfunction "GPI2")
			(pintype "input")
			(teardrops
				(best_length_ratio 0.2)
				(max_length 1)
				(best_width_ratio 0.9)
				(max_width 2)
				(curved_edges yes)
				(filter_ratio 0.9)
				(enabled yes)
				(allow_two_segments yes)
				(prefer_zone_connections yes)
			)
		)
		(pad "A68" smd rect
			(at 6.25 8.875)
			(size 0.3 1.75)
			(layers "F.Cu" "F.Mask" "F.Paste")
			(net 227 "/Com Express 7 Interfaces/PCIe_{B1x4}.TX0+")
			(pinfunction "PCIE_TX0+")
			(pintype "output")
			(teardrops
				(best_length_ratio 0.2)
				(max_length 1)
				(best_width_ratio 0.9)
				(max_width 2)
				(curved_edges yes)
				(filter_ratio 0.9)
				(enabled yes)
				(allow_two_segments yes)
				(prefer_zone_connections yes)
			)
		)
		(pad "A69" smd rect
			(at 6.75 8.875)
			(size 0.3 1.75)
			(layers "F.Cu" "F.Mask" "F.Paste")
			(net 225 "/Com Express 7 Interfaces/PCIe_{B1x4}.TX0-")
			(pinfunction "PCIE_TX0-")
			(pintype "output")
			(teardrops
				(best_length_ratio 0.2)
				(max_length 1)
				(best_width_ratio 0.9)
				(max_width 2)
				(curved_edges yes)
				(filter_ratio 0.9)
				(enabled yes)
				(allow_two_segments yes)
				(prefer_zone_connections yes)
			)
		)
		(pad "A70" smd rect
			(at 7.25 8.875)
			(size 0.3 1.75)
			(layers "F.Cu" "F.Mask" "F.Paste")
			(net 1 "GND")
			(pinfunction "GND(FIXED)")
			(pintype "passive")
			(teardrops
				(best_length_ratio 0.2)
				(max_length 1)
				(best_width_ratio 0.9)
				(max_width 2)
				(curved_edges yes)
				(filter_ratio 0.9)
				(enabled yes)
				(allow_two_segments yes)
				(prefer_zone_connections yes)
			)
		)
		(pad "A71" smd rect
			(at 7.75 8.875)
			(size 0.3 1.75)
			(layers "F.Cu" "F.Mask" "F.Paste")
			(net 324 "/Com Express 7 Interfaces/PCIe_{B2Ax4}.TX0+")
			(pinfunction "PCIE_TX8+")
			(pintype "output")
			(teardrops
				(best_length_ratio 0.2)
				(max_length 1)
				(best_width_ratio 0.9)
				(max_width 2)
				(curved_edges yes)
				(filter_ratio 0.9)
				(enabled yes)
				(allow_two_segments yes)
				(prefer_zone_connections yes)
			)
		)
		(pad "A72" smd rect
			(at 8.25 8.875)
			(size 0.3 1.75)
			(layers "F.Cu" "F.Mask" "F.Paste")
			(net 325 "/Com Express 7 Interfaces/PCIe_{B2Ax4}.TX0-")
			(pinfunction "PCIE_TX8-")
			(pintype "output")
			(teardrops
				(best_length_ratio 0.2)
				(max_length 1)
				(best_width_ratio 0.9)
				(max_width 2)
				(curved_edges yes)
				(filter_ratio 0.9)
				(enabled yes)
				(allow_two_segments yes)
				(prefer_zone_connections yes)
			)
		)
		(pad "A73" smd rect
			(at 8.75 8.875)
			(size 0.3 1.75)
			(layers "F.Cu" "F.Mask" "F.Paste")
			(net 1 "GND")
			(pinfunction "GND")
			(pintype "passive")
			(teardrops
				(best_length_ratio 0.2)
				(max_length 1)
				(best_width_ratio 0.9)
				(max_width 2)
				(curved_edges yes)
				(filter_ratio 0.9)
				(enabled yes)
				(allow_two_segments yes)
				(prefer_zone_connections yes)
			)
		)
		(pad "A74" smd rect
			(at 9.25 8.875)
			(size 0.3 1.75)
			(layers "F.Cu" "F.Mask" "F.Paste")
			(net 326 "/Com Express 7 Interfaces/PCIe_{B2Ax4}.TX1+")
			(pinfunction "PCIE_TX9+")
			(pintype "output")
			(teardrops
				(best_length_ratio 0.2)
				(max_length 1)
				(best_width_ratio 0.9)
				(max_width 2)
				(curved_edges yes)
				(filter_ratio 0.9)
				(enabled yes)
				(allow_two_segments yes)
				(prefer_zone_connections yes)
			)
		)
		(pad "A75" smd rect
			(at 9.75 8.875)
			(size 0.3 1.75)
			(layers "F.Cu" "F.Mask" "F.Paste")
			(net 327 "/Com Express 7 Interfaces/PCIe_{B2Ax4}.TX1-")
			(pinfunction "PCIE_TX9-")
			(pintype "output")
			(teardrops
				(best_length_ratio 0.2)
				(max_length 1)
				(best_width_ratio 0.9)
				(max_width 2)
				(curved_edges yes)
				(filter_ratio 0.9)
				(enabled yes)
				(allow_two_segments yes)
				(prefer_zone_connections yes)
			)
		)
		(pad "A76" smd rect
			(at 10.25 8.875)
			(size 0.3 1.75)
			(layers "F.Cu" "F.Mask" "F.Paste")
			(net 1 "GND")
			(pinfunction "GND")
			(pintype "passive")
			(teardrops
				(best_length_ratio 0.2)
				(max_length 1)
				(best_width_ratio 0.9)
				(max_width 2)
				(curved_edges yes)
				(filter_ratio 0.9)
				(enabled yes)
				(allow_two_segments yes)
				(prefer_zone_connections yes)
			)
		)
		(pad "A77" smd rect
			(at 10.75 8.875)
			(size 0.3 1.75)
			(layers "F.Cu" "F.Mask" "F.Paste")
			(net 328 "/Com Express 7 Interfaces/PCIe_{B2Ax4}.TX2+")
			(pinfunction "PCIE_TX10+")
			(pintype "output")
			(teardrops
				(best_length_ratio 0.2)
				(max_length 1)
				(best_width_ratio 0.9)
				(max_width 2)
				(curved_edges yes)
				(filter_ratio 0.9)
				(enabled yes)
				(allow_two_segments yes)
				(prefer_zone_connections yes)
			)
		)
		(pad "A78" smd rect
			(at 11.25 8.875)
			(size 0.3 1.75)
			(layers "F.Cu" "F.Mask" "F.Paste")
			(net 329 "/Com Express 7 Interfaces/PCIe_{B2Ax4}.TX2-")
			(pinfunction "PCIE_TX10-")
			(pintype "output")
			(teardrops
				(best_length_ratio 0.2)
				(max_length 1)
				(best_width_ratio 0.9)
				(max_width 2)
				(curved_edges yes)
				(filter_ratio 0.9)
				(enabled yes)
				(allow_two_segments yes)
				(prefer_zone_connections yes)
			)
		)
	)
)
